(kicad_pcb
	(version 20260206)
	(generator "pcbnew")
	(generator_version "10.0")
	(general
		(thickness 1.6)
		(legacy_teardrops no)
	)
	(paper "A4")
	(title_block
		(title "peb — Lightning_PEB_BRD.brd")
		(comment 1 "Lightning (Wiwynn / Facebook NVMe JBOF) / footprints 1579-1584 of 2563")
	)
	(layers
		(0 "F.Cu" signal "TOP")
		(4 "In1.Cu" signal "L2GND")
		(6 "In2.Cu" signal "L3")
		(8 "In3.Cu" signal "L4VCC")
		(10 "In4.Cu" signal "L5VCC")
		(12 "In5.Cu" signal "L6")
		(14 "In6.Cu" signal "L7GND")
		(2 "B.Cu" signal "BOTTOM")
		(9 "F.Adhes" user "F.Adhesive")
		(11 "B.Adhes" user "B.Adhesive")
		(13 "F.Paste" user "Package Geometry/Pastemask Top")
		(15 "B.Paste" user "Package Geometry/Pastemask Bottom")
		(5 "F.SilkS" user "Ref Des/Silkscreen Top")
		(7 "B.SilkS" user "Ref Des/Silkscreen Bottom")
		(1 "F.Mask" user "Board Geometry/Soldermask Top")
		(3 "B.Mask" user "Board Geometry/Soldermask Bottom")
		(17 "Dwgs.User" user "User.Drawings")
		(19 "Cmts.User" user "User.Comments")
		(21 "Eco1.User" user "User.Eco1")
		(23 "Eco2.User" user "User.Eco2")
		(25 "Edge.Cuts" user "Board Geometry/Outline")
		(27 "Margin" user)
		(31 "F.CrtYd" user "Package Geometry/Place Bound Top")
		(29 "B.CrtYd" user "Package Geometry/Place Bound Bottom")
		(35 "F.Fab" user "Ref Des/Assembly Top")
		(33 "B.Fab" user "Ref Des/Assembly Bottom")
	)
	(footprint ""
		(layer "F.Cu")
		(at 251.640594 -3.59664 -90)
		(property "Reference" "R3601"
			(at 0 0 270)
			(layer "F.SilkS")
			(hide yes)
			(effects
				(font
					(size 1.27 1.27)
				)
			)
		)
		(property "Value" "1KR2F-3-GP"
			(at 0.064008 -3.993896 270)
			(unlocked yes)
			(layer "F.Fab")
			(hide yes)
			(effects
				(font
					(size 1.016 1.016)
					(thickness 0.1524)
				)
			)
		)
		(property "Device Type" "R402H16"
			(at 0.064008 -5.517896 270)
			(unlocked yes)
			(layer "F.Fab")
			(hide yes)
			(effects
				(font
					(size 1.016 1.016)
					(thickness 0.1524)
				)
			)
		)
		(duplicate_pad_numbers_are_jumpers no)
		(fp_line
			(start -0.508 -0.9398)
			(end -0.508 0.9398)
			(stroke
				(width 0.1524)
				(type default)
			)
			(layer "F.SilkS")
		)
		(fp_line
			(start 0.508 -0.9398)
			(end -0.508 -0.9398)
			(stroke
				(width 0.1524)
				(type default)
			)
			(layer "F.SilkS")
		)
		(fp_rect
			(start -0.508 0.9398)
			(end 0.508 -0.9398)
			(stroke
				(width 0)
				(type default)
			)
			(fill no)
			(layer "F.CrtYd")
		)
		(fp_rect
			(start -0.508 0.9398)
			(end 0.508 -0.9398)
			(stroke
				(width 0)
				(type default)
			)
			(fill no)
			(layer "F.Fab")
		)
		(pad "1" smd custom
			(at 0 -0.4445 270)
			(size 0.1397 0.1397)
			(layers "F.Cu" "F.Mask" "F.Paste")
			(net "MAX6654_ADD0")
			(options
				(clearance outline)
				(anchor circle)
			)
			(primitives
				(gr_poly
					(pts
						(arc
							(start -0.1778 -0.2794)
							(mid -0.249642 -0.249642)
							(end -0.2794 -0.1778)
						)
						(arc
							(start -0.2794 0.1778)
							(mid -0.249642 0.249642)
							(end -0.1778 0.2794)
						)
						(arc
							(start 0.1778 0.2794)
							(mid 0.249642 0.249642)
							(end 0.2794 0.1778)
						)
						(arc
							(start 0.2794 -0.1778)
							(mid 0.249642 -0.249642)
							(end 0.1778 -0.2794)
						)
					)
					(width 0)
					(fill yes)
				)
			)
		)
		(pad "2" smd custom
			(at 0 0.4445 270)
			(size 0.1397 0.1397)
			(layers "F.Cu" "F.Mask" "F.Paste")
			(net "GND")
			(options
				(clearance outline)
				(anchor circle)
			)
			(primitives
				(gr_poly
					(pts
						(arc
							(start -0.1778 -0.2794)
							(mid -0.249642 -0.249642)
							(end -0.2794 -0.1778)
						)
						(arc
							(start -0.2794 0.1778)
							(mid -0.249642 0.249642)
							(end -0.1778 0.2794)
						)
						(arc
							(start 0.1778 0.2794)
							(mid 0.249642 0.249642)
							(end 0.2794 0.1778)
						)
						(arc
							(start 0.2794 -0.1778)
							(mid 0.249642 -0.249642)
							(end 0.1778 -0.2794)
						)
					)
					(width 0)
					(fill yes)
				)
			)
		)
	)
	(footprint ""
		(layer "F.Cu")
		(at 44.3738 -190.2206 90)
		(property "Reference" "C690"
			(at 0 0 90)
			(layer "F.SilkS")
			(hide yes)
			(effects
				(font
					(size 1.27 1.27)
				)
			)
		)
		(property "Value" "SC220P50V3JN-GP"
			(at 0 -2.8194 90)
			(unlocked yes)
			(layer "F.Fab")
			(hide yes)
			(effects
				(font
					(size 1.016 1.016)
					(thickness 0.1524)
				)
			)
		)
		(property "Device Type" "C603H36"
			(at 0 -4.3434 90)
			(unlocked yes)
			(layer "F.Fab")
			(hide yes)
			(effects
				(font
					(size 1.016 1.016)
					(thickness 0.1524)
				)
			)
		)
		(duplicate_pad_numbers_are_jumpers no)
		(fp_line
			(start 0.508 0)
			(end -0.508 0)
			(stroke
				(width 0.2032)
				(type default)
			)
			(layer "F.SilkS")
		)
		(fp_rect
			(start -0.5842 1.3335)
			(end 0.5842 -1.3335)
			(stroke
				(width 0)
				(type default)
			)
			(fill no)
			(layer "F.CrtYd")
		)
		(fp_rect
			(start -0.5842 1.3335)
			(end 0.5842 -1.3335)
			(stroke
				(width 0)
				(type default)
			)
			(fill no)
			(layer "F.Fab")
		)
		(pad "1" smd custom
			(at 0 -0.762 90)
			(size 0.2159 0.2159)
			(layers "F.Cu" "F.Mask" "F.Paste")
			(net "BUF_I2C9_CLKBUF2_SCL_R")
			(options
				(clearance outline)
				(anchor circle)
			)
			(primitives
				(gr_poly
					(pts
						(arc
							(start -0.3302 -0.4318)
							(mid -0.402042 -0.402042)
							(end -0.4318 -0.3302)
						)
						(arc
							(start -0.4318 0.3302)
							(mid -0.402042 0.402042)
							(end -0.3302 0.4318)
						)
						(arc
							(start 0.3302 0.4318)
							(mid 0.402042 0.402042)
							(end 0.4318 0.3302)
						)
						(arc
							(start 0.4318 -0.3302)
							(mid 0.402042 -0.402042)
							(end 0.3302 -0.4318)
						)
					)
					(width 0)
					(fill yes)
				)
			)
		)
		(pad "2" smd custom
			(at 0 0.762 90)
			(size 0.2159 0.2159)
			(layers "F.Cu" "F.Mask" "F.Paste")
			(net "GND")
			(options
				(clearance outline)
				(anchor circle)
			)
			(primitives
				(gr_poly
					(pts
						(arc
							(start -0.3302 -0.4318)
							(mid -0.402042 -0.402042)
							(end -0.4318 -0.3302)
						)
						(arc
							(start -0.4318 0.3302)
							(mid -0.402042 0.402042)
							(end -0.3302 0.4318)
						)
						(arc
							(start 0.3302 0.4318)
							(mid 0.402042 0.402042)
							(end 0.4318 0.3302)
						)
						(arc
							(start 0.4318 -0.3302)
							(mid 0.402042 -0.402042)
							(end 0.3302 -0.4318)
						)
					)
					(width 0)
					(fill yes)
				)
			)
		)
	)
	(footprint ""
		(layer "F.Cu")
		(at 17.9324 -52.0192 -90)
		(property "Reference" "D16"
			(at 0 0 270)
			(layer "F.SilkS")
			(hide yes)
			(effects
				(font
					(size 1.27 1.27)
				)
			)
		)
		(property "Value" "PGB1010603MR-GP"
			(at -0.0254 -2.8956 270)
			(unlocked yes)
			(layer "F.Fab")
			(hide yes)
			(effects
				(font
					(size 1.016 1.016)
					(thickness 0.1524)
				)
			)
		)
		(property "Device Type" "L1608-UH15"
			(at -0.0254 -4.4196 270)
			(unlocked yes)
			(layer "F.Fab")
			(hide yes)
			(effects
				(font
					(size 1.016 1.016)
					(thickness 0.1524)
				)
			)
		)
		(duplicate_pad_numbers_are_jumpers no)
		(fp_line
			(start 0.254 0)
			(end -0.254 0)
			(stroke
				(width 0.2032)
				(type default)
			)
			(layer "F.SilkS")
		)
		(fp_rect
			(start -0.5842 1.3335)
			(end 0.5842 -1.3335)
			(stroke
				(width 0)
				(type default)
			)
			(fill no)
			(layer "F.CrtYd")
		)
		(fp_rect
			(start -0.5842 1.3335)
			(end 0.5842 -1.3335)
			(stroke
				(width 0)
				(type default)
			)
			(fill no)
			(layer "F.Fab")
		)
		(pad "1" smd custom
			(at 0 -0.762 270)
			(size 0.2159 0.2159)
			(layers "F.Cu" "F.Mask" "F.Paste")
			(net "NIC0_MDI0_P2_R")
			(options
				(clearance outline)
				(anchor circle)
			)
			(primitives
				(gr_poly
					(pts
						(arc
							(start -0.3302 -0.4318)
							(mid -0.402042 -0.402042)
							(end -0.4318 -0.3302)
						)
						(arc
							(start -0.4318 0.3302)
							(mid -0.402042 0.402042)
							(end -0.3302 0.4318)
						)
						(arc
							(start 0.3302 0.4318)
							(mid 0.402042 0.402042)
							(end 0.4318 0.3302)
						)
						(arc
							(start 0.4318 -0.3302)
							(mid 0.402042 -0.402042)
							(end 0.3302 -0.4318)
						)
					)
					(width 0)
					(fill yes)
				)
			)
		)
		(pad "2" smd custom
			(at 0 0.762 270)
			(size 0.2159 0.2159)
			(layers "F.Cu" "F.Mask" "F.Paste")
			(net "GND")
			(options
				(clearance outline)
				(anchor circle)
			)
			(primitives
				(gr_poly
					(pts
						(arc
							(start -0.3302 -0.4318)
							(mid -0.402042 -0.402042)
							(end -0.4318 -0.3302)
						)
						(arc
							(start -0.4318 0.3302)
							(mid -0.402042 0.402042)
							(end -0.3302 0.4318)
						)
						(arc
							(start 0.3302 0.4318)
							(mid 0.402042 0.402042)
							(end 0.4318 0.3302)
						)
						(arc
							(start 0.4318 -0.3302)
							(mid 0.402042 -0.402042)
							(end 0.3302 -0.4318)
						)
					)
					(width 0)
					(fill yes)
				)
			)
		)
	)
	(footprint ""
		(layer "F.Cu")
		(at 347.527372 -45.110908)
		(property "Reference" "Q37"
			(at 0 0 0)
			(layer "F.SilkS")
			(hide yes)
			(effects
				(font
					(size 1.27 1.27)
				)
			)
		)
		(property "Value" "2N7002K-1-GP"
			(at 0.127 -8.9662 0)
			(unlocked yes)
			(layer "F.Fab")
			(hide yes)
			(effects
				(font
					(size 1.016 1.016)
					(thickness 0.1524)
				)
			)
		)
		(property "Device Type" "SOT23DGS2D4H44"
			(at 0.127 -10.4902 0)
			(unlocked yes)
			(layer "F.Fab")
			(hide yes)
			(effects
				(font
					(size 1.016 1.016)
					(thickness 0.1524)
				)
			)
		)
		(duplicate_pad_numbers_are_jumpers no)
		(fp_line
			(start -1.651 -1.778)
			(end -1.651 1.778)
			(stroke
				(width 0.1524)
				(type default)
			)
			(layer "F.SilkS")
		)
		(fp_line
			(start -1.651 1.778)
			(end 1.651 1.778)
			(stroke
				(width 0.1524)
				(type default)
			)
			(layer "F.SilkS")
		)
		(fp_line
			(start 1.651 -1.778)
			(end -1.651 -1.778)
			(stroke
				(width 0.1524)
				(type default)
			)
			(layer "F.SilkS")
		)
		(fp_line
			(start 1.651 1.778)
			(end 1.651 -1.778)
			(stroke
				(width 0.1524)
				(type default)
			)
			(layer "F.SilkS")
		)
		(fp_poly
			(pts
				(xy -1.778 1.8796) (xy -1.778 -1.8796) (xy 1.778 -1.8796) (xy 1.778 1.8796)
			)
			(stroke
				(width 0)
				(type default)
			)
			(fill no)
			(layer "F.CrtYd")
		)
		(fp_poly
			(pts
				(xy -1.778 1.8796) (xy -1.778 -1.8796) (xy 1.778 -1.8796) (xy 1.778 1.8796)
			)
			(stroke
				(width 0)
				(type default)
			)
			(fill no)
			(layer "F.Fab")
		)
		(pad "D" smd custom
			(at 0 -0.9525)
			(size 0.1905 0.1905)
			(layers "F.Cu" "F.Mask" "F.Paste")
			(net "PE1_PERST#_R")
			(options
				(clearance outline)
				(anchor circle)
			)
			(primitives
				(gr_poly
					(pts
						(arc
							(start -0.1778 0.5715)
							(mid -0.321484 0.511984)
							(end -0.381 0.3683)
						)
						(arc
							(start -0.381 -0.3683)
							(mid -0.321484 -0.511984)
							(end -0.1778 -0.5715)
						)
						(arc
							(start 0.1778 -0.5715)
							(mid 0.321484 -0.511984)
							(end 0.381 -0.3683)
						)
						(arc
							(start 0.381 0.3683)
							(mid 0.321484 0.511984)
							(end 0.1778 0.5715)
						)
					)
					(width 0)
					(fill yes)
				)
			)
		)
		(pad "G" smd custom
			(at -0.98425 0.9525)
			(size 0.1905 0.1905)
			(layers "F.Cu" "F.Mask" "F.Paste")
			(net "Q37_G")
			(options
				(clearance outline)
				(anchor circle)
			)
			(primitives
				(gr_poly
					(pts
						(arc
							(start -0.1778 0.5715)
							(mid -0.321484 0.511984)
							(end -0.381 0.3683)
						)
						(arc
							(start -0.381 -0.3683)
							(mid -0.321484 -0.511984)
							(end -0.1778 -0.5715)
						)
						(arc
							(start 0.1778 -0.5715)
							(mid 0.321484 -0.511984)
							(end 0.381 -0.3683)
						)
						(arc
							(start 0.381 0.3683)
							(mid 0.321484 0.511984)
							(end 0.1778 0.5715)
						)
					)
					(width 0)
					(fill yes)
				)
			)
		)
		(pad "S" smd custom
			(at 0.98425 0.9525)
			(size 0.1905 0.1905)
			(layers "F.Cu" "F.Mask" "F.Paste")
			(net "PE1_PERST#")
			(options
				(clearance outline)
				(anchor circle)
			)
			(primitives
				(gr_poly
					(pts
						(arc
							(start -0.1778 0.5715)
							(mid -0.321484 0.511984)
							(end -0.381 0.3683)
						)
						(arc
							(start -0.381 -0.3683)
							(mid -0.321484 -0.511984)
							(end -0.1778 -0.5715)
						)
						(arc
							(start 0.1778 -0.5715)
							(mid 0.321484 -0.511984)
							(end 0.381 -0.3683)
						)
						(arc
							(start 0.381 0.3683)
							(mid 0.321484 0.511984)
							(end 0.1778 0.5715)
						)
					)
					(width 0)
					(fill yes)
				)
			)
		)
	)
	(footprint ""
		(layer "F.Cu")
		(at 25.6286 -48.8696 180)
		(property "Reference" "C335"
			(at 0 0 180)
			(layer "F.SilkS")
			(hide yes)
			(effects
				(font
					(size 1.27 1.27)
				)
			)
		)
		(property "Value" "SCD1U16V2KX-3GP"
			(at 1.1811 -2.7051 180)
			(unlocked yes)
			(layer "F.Fab")
			(hide yes)
			(effects
				(font
					(size 1.016 1.016)
					(thickness 0.1524)
				)
			)
		)
		(property "Device Type" "C402H22"
			(at 1.1811 -4.2291 180)
			(unlocked yes)
			(layer "F.Fab")
			(hide yes)
			(effects
				(font
					(size 1.016 1.016)
					(thickness 0.1524)
				)
			)
		)
		(duplicate_pad_numbers_are_jumpers no)
		(fp_rect
			(start -0.4318 0.9525)
			(end 0.4318 -0.9525)
			(stroke
				(width 0)
				(type default)
			)
			(fill no)
			(layer "F.CrtYd")
		)
		(fp_rect
			(start -0.4318 0.9525)
			(end 0.4318 -0.9525)
			(stroke
				(width 0)
				(type default)
			)
			(fill no)
			(layer "F.Fab")
		)
		(pad "1" smd custom
			(at 0 -0.4445 180)
			(size 0.1524 0.1524)
			(layers "F.Cu" "F.Mask" "F.Paste")
			(net "NIC0_CT_POWER")
			(options
				(clearance outline)
				(anchor circle)
			)
			(primitives
				(gr_poly
					(pts
						(arc
							(start 0.3048 -0.2032)
							(mid 0.275042 -0.275042)
							(end 0.2032 -0.3048)
						)
						(arc
							(start -0.2032 -0.3048)
							(mid -0.275042 -0.275042)
							(end -0.3048 -0.2032)
						)
						(arc
							(start -0.3048 0.2032)
							(mid -0.275042 0.275042)
							(end -0.2032 0.3048)
						)
						(arc
							(start 0.2032 0.3048)
							(mid 0.275042 0.275042)
							(end 0.3048 0.2032)
						)
					)
					(width 0)
					(fill yes)
				)
			)
		)
		(pad "2" smd custom
			(at 0 0.4445 180)
			(size 0.1524 0.1524)
			(layers "F.Cu" "F.Mask" "F.Paste")
			(net "GND")
			(options
				(clearance outline)
				(anchor circle)
			)
			(primitives
				(gr_poly
					(pts
						(arc
							(start 0.3048 -0.2032)
							(mid 0.275042 -0.275042)
							(end 0.2032 -0.3048)
						)
						(arc
							(start -0.2032 -0.3048)
							(mid -0.275042 -0.275042)
							(end -0.3048 -0.2032)
						)
						(arc
							(start -0.3048 0.2032)
							(mid -0.275042 0.275042)
							(end -0.2032 0.3048)
						)
						(arc
							(start 0.2032 0.3048)
							(mid 0.275042 0.275042)
							(end 0.3048 0.2032)
						)
					)
					(width 0)
					(fill yes)
				)
			)
		)
	)
	(footprint ""
		(layer "F.Cu")
		(at 12.0142 -180.6956)
		(property "Reference" "C7272"
			(at 0 0 0)
			(layer "F.SilkS")
			(hide yes)
			(effects
				(font
					(size 1.27 1.27)
				)
			)
		)
		(property "Value" "SCD1U16V2KX-3GP"
			(at 1.1811 -2.7051 0)
			(unlocked yes)
			(layer "F.Fab")
			(hide yes)
			(effects
				(font
					(size 1.016 1.016)
					(thickness 0.1524)
				)
			)
		)
		(property "Device Type" "C402H22"
			(at 1.1811 -4.2291 0)
			(unlocked yes)
			(layer "F.Fab")
			(hide yes)
			(effects
				(font
					(size 1.016 1.016)
					(thickness 0.1524)
				)
			)
		)
		(duplicate_pad_numbers_are_jumpers no)
		(fp_rect
			(start -0.4318 0.9525)
			(end 0.4318 -0.9525)
			(stroke
				(width 0)
				(type default)
			)
			(fill no)
			(layer "F.CrtYd")
		)
		(fp_rect
			(start -0.4318 0.9525)
			(end 0.4318 -0.9525)
			(stroke
				(width 0)
				(type default)
			)
			(fill no)
			(layer "F.Fab")
		)
		(pad "1" smd custom
			(at 0 -0.4445)
			(size 0.1524 0.1524)
			(layers "F.Cu" "F.Mask" "F.Paste")
			(net "MB0_CM_VOUT_R")
			(options
				(clearance outline)
				(anchor circle)
			)
			(primitives
				(gr_poly
					(pts
						(arc
							(start 0.3048 -0.2032)
							(mid 0.275042 -0.275042)
							(end 0.2032 -0.3048)
						)
						(arc
							(start -0.2032 -0.3048)
							(mid -0.275042 -0.275042)
							(end -0.3048 -0.2032)
						)
						(arc
							(start -0.3048 0.2032)
							(mid -0.275042 0.275042)
							(end -0.2032 0.3048)
						)
						(arc
							(start 0.2032 0.3048)
							(mid 0.275042 0.275042)
							(end 0.3048 0.2032)
						)
					)
					(width 0)
					(fill yes)
				)
			)
		)
		(pad "2" smd custom
			(at 0 0.4445)
			(size 0.1524 0.1524)
			(layers "F.Cu" "F.Mask" "F.Paste")
			(net "AGND_CURRENT_MON")
			(options
				(clearance outline)
				(anchor circle)
			)
			(primitives
				(gr_poly
					(pts
						(arc
							(start 0.3048 -0.2032)
							(mid 0.275042 -0.275042)
							(end 0.2032 -0.3048)
						)
						(arc
							(start -0.2032 -0.3048)
							(mid -0.275042 -0.275042)
							(end -0.3048 -0.2032)
						)
						(arc
							(start -0.3048 0.2032)
							(mid -0.275042 0.275042)
							(end -0.2032 0.3048)
						)
						(arc
							(start 0.2032 0.3048)
							(mid 0.275042 0.275042)
							(end 0.3048 0.2032)
						)
					)
					(width 0)
					(fill yes)
				)
			)
		)
	)
)
